(kicad_pcb
	(version 20260206)
	(generator "pcbnew")
	(generator_version "10.0")
	(general
		(thickness 1.6)
		(legacy_teardrops no)
	)
	(paper "A4")
	(title_block
		(title "panther-plus-userver — 13130-1b_20150205.brd")
		(comment 1 "Honey Badger (Wiwynn) / footprints 1160-1168 of 1509")
	)
	(layers
		(0 "F.Cu" signal "TOP")
		(4 "In1.Cu" signal "L2")
		(6 "In2.Cu" signal "L3")
		(8 "In3.Cu" signal "L4")
		(10 "In4.Cu" signal "L5")
		(12 "In5.Cu" signal "L6")
		(14 "In6.Cu" signal "L7")
		(16 "In7.Cu" signal "L8")
		(18 "In8.Cu" signal "L9")
		(20 "In9.Cu" signal "L10")
		(22 "In10.Cu" signal "L11")
		(2 "B.Cu" signal "BOTTOM")
		(9 "F.Adhes" user "F.Adhesive")
		(11 "B.Adhes" user "B.Adhesive")
		(13 "F.Paste" user "Package Geometry/Pastemask Top")
		(15 "B.Paste" user "Package Geometry/Pastemask Bottom")
		(5 "F.SilkS" user "Ref Des/Silkscreen Top")
		(7 "B.SilkS" user "Ref Des/Silkscreen Bottom")
		(1 "F.Mask" user "Board Geometry/Soldermask Top")
		(3 "B.Mask" user "Board Geometry/Soldermask Bottom")
		(17 "Dwgs.User" user "User.Drawings")
		(19 "Cmts.User" user "User.Comments")
		(21 "Eco1.User" user "User.Eco1")
		(23 "Eco2.User" user "User.Eco2")
		(25 "Edge.Cuts" user "Board Geometry/Outline")
		(27 "Margin" user)
		(31 "F.CrtYd" user "Package Geometry/Place Bound Top")
		(29 "B.CrtYd" user "Package Geometry/Place Bound Bottom")
		(35 "F.Fab" user "Ref Des/Assembly Top")
		(33 "B.Fab" user "Ref Des/Assembly Bottom")
	)
	(footprint ""
		(layer "B.Cu")
		(at 183.007 -29.591 90)
		(property "Reference" "PC192"
			(at 0 0 90)
			(layer "B.SilkS")
			(hide yes)
			(effects
				(font
					(size 1.27 1.27)
				)
				(justify mirror)
			)
		)
		(property "Value" "SC1500P50V2KX-2GP"
			(at -1.8923 -1.2065 90)
			(unlocked yes)
			(layer "B.Fab")
			(hide yes)
			(effects
				(font
					(size 1.016 1.016)
					(thickness 0.1524)
				)
				(justify mirror)
			)
		)
		(property "Device Type" "C402H22"
			(at -1.8923 -2.7305 90)
			(unlocked yes)
			(layer "B.Fab")
			(hide yes)
			(effects
				(font
					(size 1.016 1.016)
					(thickness 0.1524)
				)
				(justify mirror)
			)
		)
		(duplicate_pad_numbers_are_jumpers no)
		(fp_rect
			(start 0.381 0.7366)
			(end -0.381 -0.7366)
			(stroke
				(width 0)
				(type default)
			)
			(fill no)
			(layer "B.CrtYd")
		)
		(fp_rect
			(start 0.381 0.7366)
			(end -0.381 -0.7366)
			(stroke
				(width 0)
				(type default)
			)
			(fill no)
			(layer "B.Fab")
		)
		(pad "1" smd custom
			(at 0 -0.4572 270)
			(size 0.1143 0.1143)
			(layers "B.Cu" "B.Mask" "B.Paste")
			(net "VSENSE_PVDDR_A_VSEN_FB")
			(options
				(clearance outline)
				(anchor circle)
			)
			(primitives
				(gr_poly
					(pts
						(arc
							(start -0.254 0.1778)
							(mid -0.239121 0.213721)
							(end -0.2032 0.2286)
						)
						(arc
							(start 0.2032 0.2286)
							(mid 0.239121 0.213721)
							(end 0.254 0.1778)
						)
						(arc
							(start 0.254 -0.1778)
							(mid 0.239121 -0.213721)
							(end 0.2032 -0.2286)
						)
						(arc
							(start -0.2032 -0.2286)
							(mid -0.239121 -0.213721)
							(end -0.254 -0.1778)
						)
					)
					(width 0)
					(fill yes)
				)
			)
		)
		(pad "2" smd custom
			(at 0 0.4572 270)
			(size 0.1143 0.1143)
			(layers "B.Cu" "B.Mask" "B.Paste")
			(net "VR_PVDDR_A_VSEN")
			(options
				(clearance outline)
				(anchor circle)
			)
			(primitives
				(gr_poly
					(pts
						(arc
							(start -0.254 0.1778)
							(mid -0.239121 0.213721)
							(end -0.2032 0.2286)
						)
						(arc
							(start 0.2032 0.2286)
							(mid 0.239121 0.213721)
							(end 0.254 0.1778)
						)
						(arc
							(start 0.254 -0.1778)
							(mid 0.239121 -0.213721)
							(end 0.2032 -0.2286)
						)
						(arc
							(start -0.2032 -0.2286)
							(mid -0.239121 -0.213721)
							(end -0.254 -0.1778)
						)
					)
					(width 0)
					(fill yes)
				)
			)
		)
	)
	(footprint ""
		(layer "B.Cu")
		(at 67.183 -27.559 -90)
		(property "Reference" "C48"
			(at 0 0 90)
			(layer "B.SilkS")
			(hide yes)
			(effects
				(font
					(size 1.27 1.27)
				)
				(justify mirror)
			)
		)
		(property "Value" "SCD01U16V2KX-3GP"
			(at -1.1811 -2.7051 270)
			(unlocked yes)
			(layer "B.Fab")
			(hide yes)
			(effects
				(font
					(size 1.016 1.016)
					(thickness 0.1524)
				)
				(justify mirror)
			)
		)
		(property "Device Type" "C402H22"
			(at -1.1811 -4.2291 270)
			(unlocked yes)
			(layer "B.Fab")
			(hide yes)
			(effects
				(font
					(size 1.016 1.016)
					(thickness 0.1524)
				)
				(justify mirror)
			)
		)
		(duplicate_pad_numbers_are_jumpers no)
		(fp_rect
			(start 0.381 0.7366)
			(end -0.381 -0.7366)
			(stroke
				(width 0)
				(type default)
			)
			(fill no)
			(layer "B.CrtYd")
		)
		(fp_rect
			(start 0.381 0.7366)
			(end -0.381 -0.7366)
			(stroke
				(width 0)
				(type default)
			)
			(fill no)
			(layer "B.Fab")
		)
		(pad "1" smd custom
			(at 0 -0.4572 90)
			(size 0.1143 0.1143)
			(layers "B.Cu" "B.Mask" "B.Paste")
			(net "SATA3_TX_DP0")
			(options
				(clearance outline)
				(anchor circle)
			)
			(primitives
				(gr_poly
					(pts
						(arc
							(start -0.254 0.1778)
							(mid -0.239121 0.213721)
							(end -0.2032 0.2286)
						)
						(arc
							(start 0.2032 0.2286)
							(mid 0.239121 0.213721)
							(end 0.254 0.1778)
						)
						(arc
							(start 0.254 -0.1778)
							(mid 0.239121 -0.213721)
							(end 0.2032 -0.2286)
						)
						(arc
							(start -0.2032 -0.2286)
							(mid -0.239121 -0.213721)
							(end -0.254 -0.1778)
						)
					)
					(width 0)
					(fill yes)
				)
			)
		)
		(pad "2" smd custom
			(at 0 0.4572 90)
			(size 0.1143 0.1143)
			(layers "B.Cu" "B.Mask" "B.Paste")
			(net "SATA3_TX_C_DP0")
			(options
				(clearance outline)
				(anchor circle)
			)
			(primitives
				(gr_poly
					(pts
						(arc
							(start -0.254 0.1778)
							(mid -0.239121 0.213721)
							(end -0.2032 0.2286)
						)
						(arc
							(start 0.2032 0.2286)
							(mid 0.239121 0.213721)
							(end 0.254 0.1778)
						)
						(arc
							(start 0.254 -0.1778)
							(mid 0.239121 -0.213721)
							(end 0.2032 -0.2286)
						)
						(arc
							(start -0.2032 -0.2286)
							(mid -0.239121 -0.213721)
							(end -0.254 -0.1778)
						)
					)
					(width 0)
					(fill yes)
				)
			)
		)
	)
	(footprint ""
		(layer "B.Cu")
		(at 113.538 -45.466 180)
		(property "Reference" "C179"
			(at 0 0 0)
			(layer "B.SilkS")
			(hide yes)
			(effects
				(font
					(size 1.27 1.27)
				)
				(justify mirror)
			)
		)
		(property "Value" "SC22U6D3V5MX-2GP"
			(at 0.0762 -6.1214 180)
			(unlocked yes)
			(layer "B.Fab")
			(hide yes)
			(effects
				(font
					(size 1.016 1.016)
					(thickness 0.1524)
				)
				(justify mirror)
			)
		)
		(property "Device Type" "C805H58"
			(at 0.0762 -8.1534 180)
			(unlocked yes)
			(layer "B.Fab")
			(hide yes)
			(effects
				(font
					(size 1.016 1.016)
					(thickness 0.1524)
				)
				(justify mirror)
			)
		)
		(duplicate_pad_numbers_are_jumpers no)
		(fp_line
			(start -0.6096 0)
			(end 0.6096 0)
			(stroke
				(width 0.3048)
				(type default)
			)
			(layer "B.SilkS")
		)
		(fp_poly
			(pts
				(xy 0.9017 1.4351) (xy -0.9017 1.4351) (xy -0.9017 -1.4351) (xy 0.9017 -1.4351)
			)
			(stroke
				(width 0)
				(type default)
			)
			(fill no)
			(layer "B.CrtYd")
		)
		(fp_poly
			(pts
				(xy -0.9017 1.4351) (xy -0.9017 -1.4351) (xy 0.9017 -1.4351) (xy 0.9017 1.4351)
			)
			(stroke
				(width 0)
				(type default)
			)
			(fill no)
			(layer "B.Fab")
		)
		(pad "1" smd rect
			(at 0 -0.8382)
			(size 1.5494 0.9398)
			(layers "B.Cu" "B.Mask" "B.Paste")
			(net "PVCCP")
		)
		(pad "2" smd rect
			(at 0 0.8382)
			(size 1.5494 0.9398)
			(layers "B.Cu" "B.Mask" "B.Paste")
			(net "GND")
		)
	)
	(footprint ""
		(layer "B.Cu")
		(at 16.383 -21.844 180)
		(property "Reference" "R37"
			(at 0 0 0)
			(layer "B.SilkS")
			(hide yes)
			(effects
				(font
					(size 1.27 1.27)
				)
				(justify mirror)
			)
		)
		(property "Value" "0R2J-2-GP"
			(at -1.7907 -1.1176 180)
			(unlocked yes)
			(layer "B.Fab")
			(hide yes)
			(effects
				(font
					(size 1.016 1.016)
					(thickness 0.1524)
				)
				(justify mirror)
			)
		)
		(property "Device Type" "R402H16"
			(at -1.7907 -2.6416 180)
			(unlocked yes)
			(layer "B.Fab")
			(hide yes)
			(effects
				(font
					(size 1.016 1.016)
					(thickness 0.1524)
				)
				(justify mirror)
			)
		)
		(duplicate_pad_numbers_are_jumpers no)
		(fp_rect
			(start 0.381 0.8382)
			(end -0.381 -0.8382)
			(stroke
				(width 0)
				(type default)
			)
			(fill no)
			(layer "B.CrtYd")
		)
		(fp_rect
			(start 0.381 0.8382)
			(end -0.381 -0.8382)
			(stroke
				(width 0)
				(type default)
			)
			(fill no)
			(layer "B.Fab")
		)
		(pad "1" smd custom
			(at 0 -0.4318)
			(size 0.127 0.127)
			(layers "B.Cu" "B.Mask" "B.Paste")
			(net "PWRGD_P1V0_PG")
			(options
				(clearance outline)
				(anchor circle)
			)
			(primitives
				(gr_poly
					(pts
						(arc
							(start -0.2032 0.2794)
							(mid -0.239121 0.264521)
							(end -0.254 0.2286)
						)
						(arc
							(start -0.254 -0.2286)
							(mid -0.239121 -0.264521)
							(end -0.2032 -0.2794)
						)
						(arc
							(start 0.2032 -0.2794)
							(mid 0.239121 -0.264521)
							(end 0.254 -0.2286)
						)
						(arc
							(start 0.254 0.2286)
							(mid 0.239121 0.264521)
							(end 0.2032 0.2794)
						)
					)
					(width 0)
					(fill yes)
				)
			)
		)
		(pad "2" smd custom
			(at 0 0.4318)
			(size 0.127 0.127)
			(layers "B.Cu" "B.Mask" "B.Paste")
			(net "PG_P1V0")
			(options
				(clearance outline)
				(anchor circle)
			)
			(primitives
				(gr_poly
					(pts
						(arc
							(start -0.2032 0.2794)
							(mid -0.239121 0.264521)
							(end -0.254 0.2286)
						)
						(arc
							(start -0.254 -0.2286)
							(mid -0.239121 -0.264521)
							(end -0.2032 -0.2794)
						)
						(arc
							(start 0.2032 -0.2794)
							(mid 0.239121 -0.264521)
							(end 0.254 -0.2286)
						)
						(arc
							(start 0.254 0.2286)
							(mid 0.239121 0.264521)
							(end 0.2032 0.2794)
						)
					)
					(width 0)
					(fill yes)
				)
			)
		)
	)
	(footprint ""
		(layer "B.Cu")
		(at 49.657 -27.9908 -90)
		(property "Reference" "C227"
			(at 0 0 90)
			(layer "B.SilkS")
			(hide yes)
			(effects
				(font
					(size 1.27 1.27)
				)
				(justify mirror)
			)
		)
		(property "Value" "SC1U25V3KX-GP"
			(at 0 -2.8194 270)
			(unlocked yes)
			(layer "B.Fab")
			(hide yes)
			(effects
				(font
					(size 1.016 1.016)
					(thickness 0.1524)
				)
				(justify mirror)
			)
		)
		(property "Device Type" "C603H36"
			(at 0 -4.3434 270)
			(unlocked yes)
			(layer "B.Fab")
			(hide yes)
			(effects
				(font
					(size 1.016 1.016)
					(thickness 0.1524)
				)
				(justify mirror)
			)
		)
		(duplicate_pad_numbers_are_jumpers no)
		(fp_line
			(start 0.4064 0)
			(end -0.4064 0)
			(stroke
				(width 0.2286)
				(type default)
			)
			(layer "B.SilkS")
		)
		(fp_rect
			(start 0.635 1.1811)
			(end -0.635 -1.1811)
			(stroke
				(width 0)
				(type default)
			)
			(fill no)
			(layer "B.CrtYd")
		)
		(fp_rect
			(start 0.635 1.1811)
			(end -0.635 -1.1811)
			(stroke
				(width 0)
				(type default)
			)
			(fill no)
			(layer "B.Fab")
		)
		(pad "1" smd custom
			(at 0 -0.6604 90)
			(size 0.19685 0.19685)
			(layers "B.Cu" "B.Mask" "B.Paste")
			(net "P3V3_VDDA_CLKBUFF")
			(options
				(clearance outline)
				(anchor circle)
			)
			(primitives
				(gr_poly
					(pts
						(arc
							(start 0.508 0.2921)
							(mid 0.478242 0.363942)
							(end 0.4064 0.3937)
						)
						(arc
							(start -0.4064 0.3937)
							(mid -0.478242 0.363942)
							(end -0.508 0.2921)
						)
						(arc
							(start -0.508 -0.2921)
							(mid -0.478242 -0.363942)
							(end -0.4064 -0.3937)
						)
						(arc
							(start 0.4064 -0.3937)
							(mid 0.478242 -0.363942)
							(end 0.508 -0.2921)
						)
					)
					(width 0)
					(fill yes)
				)
			)
		)
		(pad "2" smd custom
			(at 0 0.6604 90)
			(size 0.19685 0.19685)
			(layers "B.Cu" "B.Mask" "B.Paste")
			(net "GND")
			(options
				(clearance outline)
				(anchor circle)
			)
			(primitives
				(gr_poly
					(pts
						(arc
							(start 0.508 0.2921)
							(mid 0.478242 0.363942)
							(end 0.4064 0.3937)
						)
						(arc
							(start -0.4064 0.3937)
							(mid -0.478242 0.363942)
							(end -0.508 0.2921)
						)
						(arc
							(start -0.508 -0.2921)
							(mid -0.478242 -0.363942)
							(end -0.4064 -0.3937)
						)
						(arc
							(start 0.4064 -0.3937)
							(mid 0.478242 -0.363942)
							(end 0.508 -0.2921)
						)
					)
					(width 0)
					(fill yes)
				)
			)
		)
	)
	(footprint ""
		(layer "B.Cu")
		(at 134.366 -45.466 -90)
		(property "Reference" "C144"
			(at 0 0 90)
			(layer "B.SilkS")
			(hide yes)
			(effects
				(font
					(size 1.27 1.27)
				)
				(justify mirror)
			)
		)
		(property "Value" "SCD1U10V2KX-5GP"
			(at -1.1811 -2.7051 270)
			(unlocked yes)
			(layer "B.Fab")
			(hide yes)
			(effects
				(font
					(size 1.016 1.016)
					(thickness 0.1524)
				)
				(justify mirror)
			)
		)
		(property "Device Type" "C402H22"
			(at -1.1811 -4.2291 270)
			(unlocked yes)
			(layer "B.Fab")
			(hide yes)
			(effects
				(font
					(size 1.016 1.016)
					(thickness 0.1524)
				)
				(justify mirror)
			)
		)
		(duplicate_pad_numbers_are_jumpers no)
		(fp_rect
			(start 0.381 0.7366)
			(end -0.381 -0.7366)
			(stroke
				(width 0)
				(type default)
			)
			(fill no)
			(layer "B.CrtYd")
		)
		(fp_rect
			(start 0.381 0.7366)
			(end -0.381 -0.7366)
			(stroke
				(width 0)
				(type default)
			)
			(fill no)
			(layer "B.Fab")
		)
		(pad "1" smd custom
			(at 0 -0.4572 90)
			(size 0.1143 0.1143)
			(layers "B.Cu" "B.Mask" "B.Paste")
			(net "P2V5_STBY")
			(options
				(clearance outline)
				(anchor circle)
			)
			(primitives
				(gr_poly
					(pts
						(arc
							(start -0.254 0.1778)
							(mid -0.239121 0.213721)
							(end -0.2032 0.2286)
						)
						(arc
							(start 0.2032 0.2286)
							(mid 0.239121 0.213721)
							(end 0.254 0.1778)
						)
						(arc
							(start 0.254 -0.1778)
							(mid 0.239121 -0.213721)
							(end 0.2032 -0.2286)
						)
						(arc
							(start -0.2032 -0.2286)
							(mid -0.239121 -0.213721)
							(end -0.254 -0.1778)
						)
					)
					(width 0)
					(fill yes)
				)
			)
		)
		(pad "2" smd custom
			(at 0 0.4572 90)
			(size 0.1143 0.1143)
			(layers "B.Cu" "B.Mask" "B.Paste")
			(net "GND")
			(options
				(clearance outline)
				(anchor circle)
			)
			(primitives
				(gr_poly
					(pts
						(arc
							(start -0.254 0.1778)
							(mid -0.239121 0.213721)
							(end -0.2032 0.2286)
						)
						(arc
							(start 0.2032 0.2286)
							(mid 0.239121 0.213721)
							(end 0.254 0.1778)
						)
						(arc
							(start 0.254 -0.1778)
							(mid 0.239121 -0.213721)
							(end 0.2032 -0.2286)
						)
						(arc
							(start -0.2032 -0.2286)
							(mid -0.239121 -0.213721)
							(end -0.254 -0.1778)
						)
					)
					(width 0)
					(fill yes)
				)
			)
		)
	)
	(footprint ""
		(layer "B.Cu")
		(at 109.982 -31.004002 180)
		(property "Reference" "R360"
			(at 0 0 0)
			(layer "B.SilkS")
			(hide yes)
			(effects
				(font
					(size 1.27 1.27)
				)
				(justify mirror)
			)
		)
		(property "Value" "1KR2F-3-GP"
			(at -0.064008 -3.993896 180)
			(unlocked yes)
			(layer "B.Fab")
			(hide yes)
			(effects
				(font
					(size 1.016 1.016)
					(thickness 0.1524)
				)
				(justify mirror)
			)
		)
		(property "Device Type" "R402H16"
			(at -0.064008 -5.517896 180)
			(unlocked yes)
			(layer "B.Fab")
			(hide yes)
			(effects
				(font
					(size 1.016 1.016)
					(thickness 0.1524)
				)
				(justify mirror)
			)
		)
		(duplicate_pad_numbers_are_jumpers no)
		(fp_rect
			(start 0.381 0.8382)
			(end -0.381 -0.8382)
			(stroke
				(width 0)
				(type default)
			)
			(fill no)
			(layer "B.CrtYd")
		)
		(fp_rect
			(start 0.381 0.8382)
			(end -0.381 -0.8382)
			(stroke
				(width 0)
				(type default)
			)
			(fill no)
			(layer "B.Fab")
		)
		(pad "1" smd custom
			(at 0 -0.4318)
			(size 0.127 0.127)
			(layers "B.Cu" "B.Mask" "B.Paste")
			(net "PV_VDDR")
			(options
				(clearance outline)
				(anchor circle)
			)
			(primitives
				(gr_poly
					(pts
						(arc
							(start -0.2032 0.2794)
							(mid -0.239121 0.264521)
							(end -0.254 0.2286)
						)
						(arc
							(start -0.254 -0.2286)
							(mid -0.239121 -0.264521)
							(end -0.2032 -0.2794)
						)
						(arc
							(start 0.2032 -0.2794)
							(mid 0.239121 -0.264521)
							(end 0.254 -0.2286)
						)
						(arc
							(start 0.254 0.2286)
							(mid 0.239121 0.264521)
							(end 0.2032 0.2794)
						)
					)
					(width 0)
					(fill yes)
				)
			)
		)
		(pad "2" smd custom
			(at 0 0.4318)
			(size 0.127 0.127)
			(layers "B.Cu" "B.Mask" "B.Paste")
			(net "M_DRAM_PWROK")
			(options
				(clearance outline)
				(anchor circle)
			)
			(primitives
				(gr_poly
					(pts
						(arc
							(start -0.2032 0.2794)
							(mid -0.239121 0.264521)
							(end -0.254 0.2286)
						)
						(arc
							(start -0.254 -0.2286)
							(mid -0.239121 -0.264521)
							(end -0.2032 -0.2794)
						)
						(arc
							(start 0.2032 -0.2794)
							(mid 0.239121 -0.264521)
							(end 0.254 -0.2286)
						)
						(arc
							(start 0.254 0.2286)
							(mid 0.239121 0.264521)
							(end 0.2032 0.2794)
						)
					)
					(width 0)
					(fill yes)
				)
			)
		)
	)
	(footprint ""
		(layer "B.Cu")
		(at 67.437 -22.987)
		(property "Reference" "LED16"
			(at 0 0 0)
			(layer "B.SilkS")
			(hide yes)
			(effects
				(font
					(size 1.27 1.27)
				)
				(justify mirror)
			)
		)
		(property "Value" "LED-YG-51-GP"
			(at 0.0381 -2.6162 0)
			(unlocked yes)
			(layer "B.Fab")
			(hide yes)
			(effects
				(font
					(size 1.016 1.016)
					(thickness 0.1524)
				)
				(justify mirror)
			)
		)
		(property "Device Type" "LED1608AKH40"
			(at 0.0381 -4.1402 0)
			(unlocked yes)
			(layer "B.Fab")
			(hide yes)
			(effects
				(font
					(size 1.016 1.016)
					(thickness 0.1524)
				)
				(justify mirror)
			)
		)
		(duplicate_pad_numbers_are_jumpers no)
		(fp_line
			(start 0.5334 1.3081)
			(end -0.5334 1.3081)
			(stroke
				(width 0.254)
				(type default)
			)
			(layer "B.SilkS")
		)
		(fp_rect
			(start 0.6604 1.1811)
			(end -0.6604 -1.1811)
			(stroke
				(width 0)
				(type default)
			)
			(fill no)
			(layer "B.CrtYd")
		)
		(fp_rect
			(start 0.6604 1.1811)
			(end -0.6604 -1.1811)
			(stroke
				(width 0)
				(type default)
			)
			(fill no)
			(layer "B.Fab")
		)
		(pad "A" smd rect
			(at 0 -0.652526 180)
			(size 1.0668 0.8128)
			(layers "B.Cu" "B.Mask" "B.Paste")
			(net "LED_MSATA_DAS_R")
		)
		(pad "K" smd rect
			(at 0 0.652526 180)
			(size 1.0668 0.8128)
			(layers "B.Cu" "B.Mask" "B.Paste")
			(net "MSATA_ACT#")
		)
	)
	(footprint ""
		(layer "B.Cu")
		(at 98.964496 -35.622484 -90)
		(property "Reference" "TP34"
			(at 0 0 90)
			(layer "B.SilkS")
			(hide yes)
			(effects
				(font
					(size 1.27 1.27)
				)
				(justify mirror)
			)
		)
		(property "Value" "TPAD24"
			(at 0 -2.9972 270)
			(unlocked yes)
			(layer "B.Fab")
			(hide yes)
			(effects
				(font
					(size 1.016 1.016)
					(thickness 0.1524)
				)
				(justify mirror)
			)
		)
		(property "Device Type" "TPAD24"
			(at 0 -4.5212 270)
			(unlocked yes)
			(layer "B.Fab")
			(hide yes)
			(effects
				(font
					(size 1.016 1.016)
					(thickness 0.1524)
				)
				(justify mirror)
			)
		)
		(duplicate_pad_numbers_are_jumpers no)
		(fp_poly
			(pts
				(arc
					(start 0 -0.3048)
					(mid 0 0.3048)
					(end 0 -0.3048)
				)
			)
			(stroke
				(width 0)
				(type default)
			)
			(fill no)
			(layer "B.CrtYd")
		)
		(fp_poly
			(pts
				(arc
					(start 0 -0.6096)
					(mid 0 0.6096)
					(end 0 -0.6096)
				)
			)
			(stroke
				(width 0)
				(type default)
			)
			(fill no)
			(layer "B.Fab")
		)
		(pad "1" smd circle
			(at 0 0 90)
			(size 0.6096 0.6096)
			(layers "B.Cu" "B.Mask" "B.Paste")
			(net "TP_CPU_RSVD12")
		)
	)
)
